(kicad_pcb
	(version 20260206)
	(generator "pcbnew")
	(generator_version "10.0")
	(general
		(thickness 1.6)
		(legacy_teardrops no)
	)
	(paper "A4")
	(title_block
		(title "04192023_DAF0TMB3IC0_F0TG_MB_C_brd_V02_OCP.brd")
		(comment 1 "Grand Teton / footprints 6648-6654 of 8354")
	)
	(layers
		(0 "F.Cu" signal "TOP")
		(4 "In1.Cu" signal "GND")
		(6 "In2.Cu" signal "IN1")
		(8 "In3.Cu" signal "GND1")
		(10 "In4.Cu" signal "IN2")
		(12 "In5.Cu" signal "GND2")
		(14 "In6.Cu" signal "IN3")
		(16 "In7.Cu" signal "GND3")
		(18 "In8.Cu" signal "VCC")
		(20 "In9.Cu" signal "VCC1")
		(22 "In10.Cu" signal "GND4")
		(24 "In11.Cu" signal "IN4")
		(26 "In12.Cu" signal "GND5")
		(28 "In13.Cu" signal "IN5")
		(30 "In14.Cu" signal "GND6")
		(32 "In15.Cu" signal "IN6")
		(34 "In16.Cu" signal "GND7")
		(2 "B.Cu" signal "BOTTOM")
		(9 "F.Adhes" user "F.Adhesive")
		(11 "B.Adhes" user "B.Adhesive")
		(13 "F.Paste" user "Package Geometry/Pastemask Top")
		(15 "B.Paste" user "Package Geometry/Pastemask Bottom")
		(5 "F.SilkS" user "Ref Des/Silkscreen Top")
		(7 "B.SilkS" user "Ref Des/Silkscreen Bottom")
		(1 "F.Mask" user "Board Geometry/Soldermask Top")
		(3 "B.Mask" user "Board Geometry/Soldermask Bottom")
		(17 "Dwgs.User" user "User.Drawings")
		(19 "Cmts.User" user "User.Comments")
		(21 "Eco1.User" user "User.Eco1")
		(23 "Eco2.User" user "User.Eco2")
		(25 "Edge.Cuts" user "Board Geometry/Outline")
		(27 "Margin" user)
		(31 "F.CrtYd" user "Package Geometry/Place Bound Top")
		(29 "B.CrtYd" user "Package Geometry/Place Bound Bottom")
		(35 "F.Fab" user "Ref Des/Assembly Top")
		(33 "B.Fab" user "Ref Des/Assembly Bottom")
	)
	(footprint ""
		(layer "B.Cu")
		(at 117.895624 -261.255256)
		(property "Reference" "C2437"
			(at 0 0 0)
			(layer "B.SilkS")
			(hide yes)
			(effects
				(font
					(size 1.27 1.27)
				)
				(justify mirror)
			)
		)
		(property "Value" ""
			(at 0 0 0)
			(layer "B.Fab")
			(effects
				(font
					(size 1.27 1.27)
				)
				(justify mirror)
			)
		)
		(duplicate_pad_numbers_are_jumpers no)
		(fp_line
			(start -0.7874 -0.4064)
			(end -0.7874 0.4064)
			(stroke
				(width 0.1524)
				(type default)
			)
			(layer "B.SilkS")
		)
		(fp_line
			(start -0.7874 0.4064)
			(end 0.7874 0.4064)
			(stroke
				(width 0.1524)
				(type default)
			)
			(layer "B.SilkS")
		)
		(fp_line
			(start 0.7874 -0.4064)
			(end -0.7874 -0.4064)
			(stroke
				(width 0.1524)
				(type default)
			)
			(layer "B.SilkS")
		)
		(fp_line
			(start 0.7874 0.4064)
			(end 0.7874 -0.4064)
			(stroke
				(width 0.1524)
				(type default)
			)
			(layer "B.SilkS")
		)
		(fp_line
			(start -0.67945 -0.3048)
			(end -0.67945 0.3048)
			(stroke
				(width 0.1)
				(type default)
			)
			(layer "B.Fab")
		)
		(fp_line
			(start -0.67945 0.3048)
			(end -0.120396 0.3048)
			(stroke
				(width 0.1)
				(type default)
			)
			(layer "B.Fab")
		)
		(fp_line
			(start -0.12065 -0.3048)
			(end -0.67945 -0.3048)
			(stroke
				(width 0.1)
				(type default)
			)
			(layer "B.Fab")
		)
		(fp_line
			(start -0.12065 -0.2794)
			(end -0.12065 -0.3048)
			(stroke
				(width 0.1)
				(type default)
			)
			(layer "B.Fab")
		)
		(fp_line
			(start -0.120396 0.2794)
			(end 0.12065 0.2794)
			(stroke
				(width 0.1)
				(type default)
			)
			(layer "B.Fab")
		)
		(fp_line
			(start -0.120396 0.3048)
			(end -0.120396 0.2794)
			(stroke
				(width 0.1)
				(type default)
			)
			(layer "B.Fab")
		)
		(fp_line
			(start 0.12065 -0.305054)
			(end 0.12065 -0.2794)
			(stroke
				(width 0.1)
				(type default)
			)
			(layer "B.Fab")
		)
		(fp_line
			(start 0.12065 -0.2794)
			(end -0.12065 -0.2794)
			(stroke
				(width 0.1)
				(type default)
			)
			(layer "B.Fab")
		)
		(fp_line
			(start 0.12065 0.2794)
			(end 0.12065 0.3048)
			(stroke
				(width 0.1)
				(type default)
			)
			(layer "B.Fab")
		)
		(fp_line
			(start 0.12065 0.3048)
			(end 0.67945 0.3048)
			(stroke
				(width 0.1)
				(type default)
			)
			(layer "B.Fab")
		)
		(fp_line
			(start 0.67945 -0.305054)
			(end 0.12065 -0.305054)
			(stroke
				(width 0.1)
				(type default)
			)
			(layer "B.Fab")
		)
		(fp_line
			(start 0.67945 0.3048)
			(end 0.67945 -0.305054)
			(stroke
				(width 0.1)
				(type default)
			)
			(layer "B.Fab")
		)
		(pad "1" smd circle
			(at 0.40005 0 180)
			(size 0 0)
			(layers "B.Cu" "B.Mask" "B.Paste")
			(net "PVDDCR_SOC_P1")
		)
		(pad "2" smd circle
			(at -0.40005 0 180)
			(size 0 0)
			(layers "B.Cu" "B.Mask" "B.Paste")
			(net "GND")
		)
	)
	(footprint ""
		(layer "B.Cu")
		(at 127.908304 -32.867092 -90)
		(property "Reference" "C6076"
			(at 0 0 90)
			(layer "B.SilkS")
			(hide yes)
			(effects
				(font
					(size 1.27 1.27)
				)
				(justify mirror)
			)
		)
		(property "Value" ""
			(at 0 0 90)
			(layer "B.Fab")
			(effects
				(font
					(size 1.27 1.27)
				)
				(justify mirror)
			)
		)
		(duplicate_pad_numbers_are_jumpers no)
		(fp_line
			(start -0.7874 0.4064)
			(end 0.7874 0.4064)
			(stroke
				(width 0.1524)
				(type default)
			)
			(layer "B.SilkS")
		)
		(fp_line
			(start 0.7874 0.4064)
			(end 0.7874 -0.4064)
			(stroke
				(width 0.1524)
				(type default)
			)
			(layer "B.SilkS")
		)
		(fp_line
			(start -0.7874 -0.4064)
			(end -0.7874 0.4064)
			(stroke
				(width 0.1524)
				(type default)
			)
			(layer "B.SilkS")
		)
		(fp_line
			(start 0.7874 -0.4064)
			(end -0.7874 -0.4064)
			(stroke
				(width 0.1524)
				(type default)
			)
			(layer "B.SilkS")
		)
		(fp_line
			(start -0.67945 0.3048)
			(end -0.120396 0.3048)
			(stroke
				(width 0.1)
				(type default)
			)
			(layer "B.Fab")
		)
		(fp_line
			(start -0.120396 0.3048)
			(end -0.120396 0.2794)
			(stroke
				(width 0.1)
				(type default)
			)
			(layer "B.Fab")
		)
		(fp_line
			(start 0.12065 0.3048)
			(end 0.67945 0.3048)
			(stroke
				(width 0.1)
				(type default)
			)
			(layer "B.Fab")
		)
		(fp_line
			(start 0.67945 0.3048)
			(end 0.67945 -0.305054)
			(stroke
				(width 0.1)
				(type default)
			)
			(layer "B.Fab")
		)
		(fp_line
			(start -0.120396 0.2794)
			(end 0.12065 0.2794)
			(stroke
				(width 0.1)
				(type default)
			)
			(layer "B.Fab")
		)
		(fp_line
			(start 0.12065 0.2794)
			(end 0.12065 0.3048)
			(stroke
				(width 0.1)
				(type default)
			)
			(layer "B.Fab")
		)
		(fp_line
			(start -0.12065 -0.2794)
			(end -0.12065 -0.3048)
			(stroke
				(width 0.1)
				(type default)
			)
			(layer "B.Fab")
		)
		(fp_line
			(start 0.12065 -0.2794)
			(end -0.12065 -0.2794)
			(stroke
				(width 0.1)
				(type default)
			)
			(layer "B.Fab")
		)
		(fp_line
			(start -0.67945 -0.3048)
			(end -0.67945 0.3048)
			(stroke
				(width 0.1)
				(type default)
			)
			(layer "B.Fab")
		)
		(fp_line
			(start -0.12065 -0.3048)
			(end -0.67945 -0.3048)
			(stroke
				(width 0.1)
				(type default)
			)
			(layer "B.Fab")
		)
		(fp_line
			(start 0.12065 -0.305054)
			(end 0.12065 -0.2794)
			(stroke
				(width 0.1)
				(type default)
			)
			(layer "B.Fab")
		)
		(fp_line
			(start 0.67945 -0.305054)
			(end 0.12065 -0.305054)
			(stroke
				(width 0.1)
				(type default)
			)
			(layer "B.Fab")
		)
		(pad "1" smd circle
			(at 0.40005 0 90)
			(size 0 0)
			(layers "B.Cu" "B.Mask" "B.Paste")
			(net "P1V2_AUX")
		)
		(pad "2" smd circle
			(at -0.40005 0 90)
			(size 0 0)
			(layers "B.Cu" "B.Mask" "B.Paste")
			(net "GND")
		)
	)
	(footprint ""
		(layer "B.Cu")
		(at 66.747644 -337.665314 -90)
		(property "Reference" "PR269"
			(at 0 0 90)
			(layer "B.SilkS")
			(hide yes)
			(effects
				(font
					(size 1.27 1.27)
				)
				(justify mirror)
			)
		)
		(property "Value" ""
			(at 0 0 90)
			(layer "B.Fab")
			(effects
				(font
					(size 1.27 1.27)
				)
				(justify mirror)
			)
		)
		(duplicate_pad_numbers_are_jumpers no)
		(fp_line
			(start -0.7874 0.4064)
			(end 0.7874 0.4064)
			(stroke
				(width 0.1524)
				(type default)
			)
			(layer "B.SilkS")
		)
		(fp_line
			(start 0.7874 0.4064)
			(end 0.7874 -0.4064)
			(stroke
				(width 0.1524)
				(type default)
			)
			(layer "B.SilkS")
		)
		(fp_line
			(start -0.7874 -0.4064)
			(end -0.7874 0.4064)
			(stroke
				(width 0.1524)
				(type default)
			)
			(layer "B.SilkS")
		)
		(fp_line
			(start 0.7874 -0.4064)
			(end -0.7874 -0.4064)
			(stroke
				(width 0.1524)
				(type default)
			)
			(layer "B.SilkS")
		)
		(fp_line
			(start -0.67945 0.3048)
			(end -0.120396 0.3048)
			(stroke
				(width 0.1)
				(type default)
			)
			(layer "B.Fab")
		)
		(fp_line
			(start -0.120396 0.3048)
			(end -0.120396 0.2794)
			(stroke
				(width 0.1)
				(type default)
			)
			(layer "B.Fab")
		)
		(fp_line
			(start 0.12065 0.3048)
			(end 0.67945 0.3048)
			(stroke
				(width 0.1)
				(type default)
			)
			(layer "B.Fab")
		)
		(fp_line
			(start 0.67945 0.3048)
			(end 0.67945 -0.305054)
			(stroke
				(width 0.1)
				(type default)
			)
			(layer "B.Fab")
		)
		(fp_line
			(start -0.120396 0.2794)
			(end 0.12065 0.2794)
			(stroke
				(width 0.1)
				(type default)
			)
			(layer "B.Fab")
		)
		(fp_line
			(start 0.12065 0.2794)
			(end 0.12065 0.3048)
			(stroke
				(width 0.1)
				(type default)
			)
			(layer "B.Fab")
		)
		(fp_line
			(start -0.12065 -0.2794)
			(end -0.12065 -0.3048)
			(stroke
				(width 0.1)
				(type default)
			)
			(layer "B.Fab")
		)
		(fp_line
			(start 0.12065 -0.2794)
			(end -0.12065 -0.2794)
			(stroke
				(width 0.1)
				(type default)
			)
			(layer "B.Fab")
		)
		(fp_line
			(start -0.67945 -0.3048)
			(end -0.67945 0.3048)
			(stroke
				(width 0.1)
				(type default)
			)
			(layer "B.Fab")
		)
		(fp_line
			(start -0.12065 -0.3048)
			(end -0.67945 -0.3048)
			(stroke
				(width 0.1)
				(type default)
			)
			(layer "B.Fab")
		)
		(fp_line
			(start 0.12065 -0.305054)
			(end 0.12065 -0.2794)
			(stroke
				(width 0.1)
				(type default)
			)
			(layer "B.Fab")
		)
		(fp_line
			(start 0.67945 -0.305054)
			(end 0.12065 -0.305054)
			(stroke
				(width 0.1)
				(type default)
			)
			(layer "B.Fab")
		)
		(pad "1" smd circle
			(at 0.40005 0 90)
			(size 0 0)
			(layers "B.Cu" "B.Mask" "B.Paste")
			(net "PVDDCR_CPU1_P1_VOS3")
		)
		(pad "2" smd circle
			(at -0.40005 0 90)
			(size 0 0)
			(layers "B.Cu" "B.Mask" "B.Paste")
			(net "PVDDCR_CPU1_P1")
		)
	)
	(footprint ""
		(layer "B.Cu")
		(at 51.734974 -416.091116)
		(property "Reference" "C2075"
			(at 0 0 0)
			(layer "B.SilkS")
			(hide yes)
			(effects
				(font
					(size 1.27 1.27)
				)
				(justify mirror)
			)
		)
		(property "Value" ""
			(at 0 0 0)
			(layer "B.Fab")
			(effects
				(font
					(size 1.27 1.27)
				)
				(justify mirror)
			)
		)
		(duplicate_pad_numbers_are_jumpers no)
		(fp_line
			(start -0.299974 -0.150114)
			(end -0.299974 0.150114)
			(stroke
				(width 0.1)
				(type default)
			)
			(layer "B.Fab")
		)
		(fp_line
			(start -0.299974 0.150114)
			(end 0.299974 0.150114)
			(stroke
				(width 0.1)
				(type default)
			)
			(layer "B.Fab")
		)
		(fp_line
			(start 0.299974 -0.150114)
			(end -0.299974 -0.150114)
			(stroke
				(width 0.1)
				(type default)
			)
			(layer "B.Fab")
		)
		(fp_line
			(start 0.299974 0.150114)
			(end 0.299974 -0.150114)
			(stroke
				(width 0.1)
				(type default)
			)
			(layer "B.Fab")
		)
		(pad "1" smd rect
			(at 0.2667 0 180)
			(size 0.3048 0.381)
			(layers "B.Cu" "B.Mask" "B.Paste")
			(net "P3E_CPU1_P5_TX_C_DP<0>")
		)
		(pad "2" smd rect
			(at -0.2667 0 180)
			(size 0.3048 0.381)
			(layers "B.Cu" "B.Mask" "B.Paste")
			(net "P3E_CPU1_P5_TX_DP<0>")
		)
	)
	(footprint ""
		(layer "B.Cu")
		(at 450.177916 -47.505366 90)
		(property "Reference" "PC2344"
			(at 0 0 90)
			(layer "B.SilkS")
			(hide yes)
			(effects
				(font
					(size 1.27 1.27)
				)
				(justify mirror)
			)
		)
		(property "Value" ""
			(at 0 0 90)
			(layer "B.Fab")
			(effects
				(font
					(size 1.27 1.27)
				)
				(justify mirror)
			)
		)
		(duplicate_pad_numbers_are_jumpers no)
		(fp_line
			(start 1.524 -0.762)
			(end -1.524 -0.762)
			(stroke
				(width 0.1524)
				(type default)
			)
			(layer "B.SilkS")
		)
		(fp_line
			(start -1.524 -0.762)
			(end -1.524 0.762)
			(stroke
				(width 0.1524)
				(type default)
			)
			(layer "B.SilkS")
		)
		(fp_line
			(start 1.524 0.762)
			(end 1.524 -0.762)
			(stroke
				(width 0.1524)
				(type default)
			)
			(layer "B.SilkS")
		)
		(fp_line
			(start -1.524 0.762)
			(end 1.524 0.762)
			(stroke
				(width 0.1524)
				(type default)
			)
			(layer "B.SilkS")
		)
		(fp_line
			(start 1.1049 -0.724916)
			(end 1.1049 0.724916)
			(stroke
				(width 0.1)
				(type default)
			)
			(layer "B.Fab")
		)
		(fp_line
			(start -1.1049 -0.724916)
			(end 1.1049 -0.724916)
			(stroke
				(width 0.1)
				(type default)
			)
			(layer "B.Fab")
		)
		(fp_line
			(start 1.1049 0.724916)
			(end -1.1049 0.724916)
			(stroke
				(width 0.1)
				(type default)
			)
			(layer "B.Fab")
		)
		(fp_line
			(start -1.1049 0.724916)
			(end -1.1049 -0.724916)
			(stroke
				(width 0.1)
				(type default)
			)
			(layer "B.Fab")
		)
		(pad "1" smd rect
			(at 0.889 0 90)
			(size 1.016 1.27)
			(layers "B.Cu" "B.Mask" "B.Paste")
			(net "SW_P3V3_AUX_FLT")
		)
		(pad "2" smd rect
			(at -0.889 0 90)
			(size 1.016 1.27)
			(layers "B.Cu" "B.Mask" "B.Paste")
			(net "GND")
		)
	)
	(footprint ""
		(layer "B.Cu")
		(at 396.218918 -203.879958 -90)
		(property "Reference" "R6131"
			(at 0 0 90)
			(layer "B.SilkS")
			(hide yes)
			(effects
				(font
					(size 1.27 1.27)
				)
				(justify mirror)
			)
		)
		(property "Value" ""
			(at 0 0 90)
			(layer "B.Fab")
			(effects
				(font
					(size 1.27 1.27)
				)
				(justify mirror)
			)
		)
		(duplicate_pad_numbers_are_jumpers no)
		(fp_line
			(start -0.7874 0.4064)
			(end 0.7874 0.4064)
			(stroke
				(width 0.1524)
				(type default)
			)
			(layer "B.SilkS")
		)
		(fp_line
			(start 0.7874 0.4064)
			(end 0.7874 -0.4064)
			(stroke
				(width 0.1524)
				(type default)
			)
			(layer "B.SilkS")
		)
		(fp_line
			(start -0.7874 -0.4064)
			(end -0.7874 0.4064)
			(stroke
				(width 0.1524)
				(type default)
			)
			(layer "B.SilkS")
		)
		(fp_line
			(start 0.7874 -0.4064)
			(end -0.7874 -0.4064)
			(stroke
				(width 0.1524)
				(type default)
			)
			(layer "B.SilkS")
		)
		(fp_line
			(start -0.67945 0.3048)
			(end -0.120396 0.3048)
			(stroke
				(width 0.1)
				(type default)
			)
			(layer "B.Fab")
		)
		(fp_line
			(start -0.120396 0.3048)
			(end -0.120396 0.2794)
			(stroke
				(width 0.1)
				(type default)
			)
			(layer "B.Fab")
		)
		(fp_line
			(start 0.12065 0.3048)
			(end 0.67945 0.3048)
			(stroke
				(width 0.1)
				(type default)
			)
			(layer "B.Fab")
		)
		(fp_line
			(start 0.67945 0.3048)
			(end 0.67945 -0.305054)
			(stroke
				(width 0.1)
				(type default)
			)
			(layer "B.Fab")
		)
		(fp_line
			(start -0.120396 0.2794)
			(end 0.12065 0.2794)
			(stroke
				(width 0.1)
				(type default)
			)
			(layer "B.Fab")
		)
		(fp_line
			(start 0.12065 0.2794)
			(end 0.12065 0.3048)
			(stroke
				(width 0.1)
				(type default)
			)
			(layer "B.Fab")
		)
		(fp_line
			(start -0.12065 -0.2794)
			(end -0.12065 -0.3048)
			(stroke
				(width 0.1)
				(type default)
			)
			(layer "B.Fab")
		)
		(fp_line
			(start 0.12065 -0.2794)
			(end -0.12065 -0.2794)
			(stroke
				(width 0.1)
				(type default)
			)
			(layer "B.Fab")
		)
		(fp_line
			(start -0.67945 -0.3048)
			(end -0.67945 0.3048)
			(stroke
				(width 0.1)
				(type default)
			)
			(layer "B.Fab")
		)
		(fp_line
			(start -0.12065 -0.3048)
			(end -0.67945 -0.3048)
			(stroke
				(width 0.1)
				(type default)
			)
			(layer "B.Fab")
		)
		(fp_line
			(start 0.12065 -0.305054)
			(end 0.12065 -0.2794)
			(stroke
				(width 0.1)
				(type default)
			)
			(layer "B.Fab")
		)
		(fp_line
			(start 0.67945 -0.305054)
			(end 0.12065 -0.305054)
			(stroke
				(width 0.1)
				(type default)
			)
			(layer "B.Fab")
		)
		(pad "1" smd circle
			(at 0.40005 0 90)
			(size 0 0)
			(layers "B.Cu" "B.Mask" "B.Paste")
			(net "PVDD18_S5_P0")
		)
		(pad "2" smd circle
			(at -0.40005 0 90)
			(size 0 0)
			(layers "B.Cu" "B.Mask" "B.Paste")
			(net "FAB_REV_ID1")
		)
	)
	(footprint ""
		(layer "B.Cu")
		(at 33.467294 -194.885564 180)
		(property "Reference" "R772"
			(at 0 0 0)
			(layer "B.SilkS")
			(hide yes)
			(effects
				(font
					(size 1.27 1.27)
				)
				(justify mirror)
			)
		)
		(property "Value" ""
			(at 0 0 0)
			(layer "B.Fab")
			(effects
				(font
					(size 1.27 1.27)
				)
				(justify mirror)
			)
		)
		(duplicate_pad_numbers_are_jumpers no)
		(fp_line
			(start 0.7874 0.4064)
			(end 0.7874 -0.4064)
			(stroke
				(width 0.1524)
				(type default)
			)
			(layer "B.SilkS")
		)
		(fp_line
			(start 0.7874 -0.4064)
			(end -0.7874 -0.4064)
			(stroke
				(width 0.1524)
				(type default)
			)
			(layer "B.SilkS")
		)
		(fp_line
			(start -0.7874 0.4064)
			(end 0.7874 0.4064)
			(stroke
				(width 0.1524)
				(type default)
			)
			(layer "B.SilkS")
		)
		(fp_line
			(start -0.7874 -0.4064)
			(end -0.7874 0.4064)
			(stroke
				(width 0.1524)
				(type default)
			)
			(layer "B.SilkS")
		)
		(fp_line
			(start 0.67945 0.3048)
			(end 0.67945 -0.305054)
			(stroke
				(width 0.1)
				(type default)
			)
			(layer "B.Fab")
		)
		(fp_line
			(start 0.67945 -0.305054)
			(end 0.12065 -0.305054)
			(stroke
				(width 0.1)
				(type default)
			)
			(layer "B.Fab")
		)
		(fp_line
			(start 0.12065 0.3048)
			(end 0.67945 0.3048)
			(stroke
				(width 0.1)
				(type default)
			)
			(layer "B.Fab")
		)
		(fp_line
			(start 0.12065 0.2794)
			(end 0.12065 0.3048)
			(stroke
				(width 0.1)
				(type default)
			)
			(layer "B.Fab")
		)
		(fp_line
			(start 0.12065 -0.2794)
			(end -0.12065 -0.2794)
			(stroke
				(width 0.1)
				(type default)
			)
			(layer "B.Fab")
		)
		(fp_line
			(start 0.12065 -0.305054)
			(end 0.12065 -0.2794)
			(stroke
				(width 0.1)
				(type default)
			)
			(layer "B.Fab")
		)
		(fp_line
			(start -0.120396 0.3048)
			(end -0.120396 0.2794)
			(stroke
				(width 0.1)
				(type default)
			)
			(layer "B.Fab")
		)
		(fp_line
			(start -0.120396 0.2794)
			(end 0.12065 0.2794)
			(stroke
				(width 0.1)
				(type default)
			)
			(layer "B.Fab")
		)
		(fp_line
			(start -0.12065 -0.2794)
			(end -0.12065 -0.3048)
			(stroke
				(width 0.1)
				(type default)
			)
			(layer "B.Fab")
		)
		(fp_line
			(start -0.12065 -0.3048)
			(end -0.67945 -0.3048)
			(stroke
				(width 0.1)
				(type default)
			)
			(layer "B.Fab")
		)
		(fp_line
			(start -0.67945 0.3048)
			(end -0.120396 0.3048)
			(stroke
				(width 0.1)
				(type default)
			)
			(layer "B.Fab")
		)
		(fp_line
			(start -0.67945 -0.3048)
			(end -0.67945 0.3048)
			(stroke
				(width 0.1)
				(type default)
			)
			(layer "B.Fab")
		)
		(pad "1" smd circle
			(at 0.40005 0)
			(size 0 0)
			(layers "B.Cu" "B.Mask" "B.Paste")
			(net "PD_CHD_CPU1_DIMM_SAA")
		)
		(pad "2" smd circle
			(at -0.40005 0)
			(size 0 0)
			(layers "B.Cu" "B.Mask" "B.Paste")
			(net "GND")
		)
	)
)
